FILE_TYPE = MACRO_DRAWING;
SET COLOR_WIRE YELLOW;
SET COLOR_PROP ORANGE;
SET COLOR_DOT WHITE;
SET COLOR_ARC YELLOW;
SET COLOR_BODY GREEN;
SET COLOR_NOTE PURPLE;
SET PROP_DISPLAY VALUE;
SET PAGE_NUMBER P68;
FORCEADD SOCKET4677_AZIF0045P001C01CS..28
(-875 2325);
FORCEPROP 1 LAST PART_NUMBER DGA^7000023
J 0
(-1925 3575);
DISPLAY 0.723404 (-1925 3575);
PAINT GREEN (-1925 3575);
DISPLAY INVISIBLE (-1925 3575);
FORCEPROP 2 LAST PART_TYPE SMLF
J 0
(-1925 3750);
DISPLAY 1.021277 (-1925 3750);
FORCEPROP 1 LAST MATERIAL IO
J 0
(-1925 3500);
DISPLAY 0.723404 (-1925 3500);
PAINT GREEN (-1925 3500);
FORCEPROP 2 LAST VALUE SOCKET4677_AZIF0045-P001C01CS
J 0
(-1925 3700);
DISPLAY 1.021277 (-1925 3700);
FORCEPROP 1 LAST $LOCATION U1
J 0
(-1925 3650);
DISPLAY 0.723404 (-1925 3650);
PAINT GREEN (-1925 3650);
FORCEPROP 0 LASTPIN (-2075 1350) $PN BD91
J 2
(-2085 1360);
DISPLAY 0.680851 (-2085 1360);
PAINT MONO (-2085 1360);
FORCEPROP 0 LASTPIN (-2075 1400) $PN BE86
J 2
(-2085 1410);
DISPLAY 0.680851 (-2085 1410);
PAINT MONO (-2085 1410);
FORCEPROP 0 LASTPIN (-2075 1450) $PN BE88
J 2
(-2085 1460);
DISPLAY 0.680851 (-2085 1460);
PAINT MONO (-2085 1460);
FORCEPROP 0 LASTPIN (-2075 1500) $PN BE90
J 2
(-2085 1510);
DISPLAY 0.680851 (-2085 1510);
PAINT MONO (-2085 1510);
FORCEPROP 0 LASTPIN (-2075 1550) $PN BF85
J 2
(-2085 1560);
DISPLAY 0.680851 (-2085 1560);
PAINT MONO (-2085 1560);
FORCEPROP 0 LASTPIN (-2075 1600) $PN BF87
J 2
(-2085 1610);
DISPLAY 0.680851 (-2085 1610);
PAINT MONO (-2085 1610);
FORCEPROP 0 LASTPIN (-2075 1650) $PN BF89
J 2
(-2085 1660);
DISPLAY 0.680851 (-2085 1660);
PAINT MONO (-2085 1660);
FORCEPROP 0 LASTPIN (-2075 1700) $PN BF91
J 2
(-2085 1710);
DISPLAY 0.680851 (-2085 1710);
PAINT MONO (-2085 1710);
FORCEPROP 0 LASTPIN (-2075 1750) $PN BG84
J 2
(-2085 1760);
DISPLAY 0.680851 (-2085 1760);
PAINT MONO (-2085 1760);
FORCEPROP 0 LASTPIN (-2075 1800) $PN BG86
J 2
(-2085 1810);
DISPLAY 0.680851 (-2085 1810);
PAINT MONO (-2085 1810);
FORCEPROP 0 LASTPIN (-2075 1850) $PN BG88
J 2
(-2085 1860);
DISPLAY 0.680851 (-2085 1860);
PAINT MONO (-2085 1860);
FORCEPROP 0 LASTPIN (-2075 1900) $PN BG90
J 2
(-2085 1910);
DISPLAY 0.680851 (-2085 1910);
PAINT MONO (-2085 1910);
FORCEPROP 0 LASTPIN (-2075 1950) $PN BH85
J 2
(-2085 1960);
DISPLAY 0.680851 (-2085 1960);
PAINT MONO (-2085 1960);
FORCEPROP 0 LASTPIN (-2075 2000) $PN BH87
J 2
(-2085 2010);
DISPLAY 0.680851 (-2085 2010);
PAINT MONO (-2085 2010);
FORCEPROP 0 LASTPIN (-2075 2050) $PN BH89
J 2
(-2085 2060);
DISPLAY 0.680851 (-2085 2060);
PAINT MONO (-2085 2060);
FORCEPROP 0 LASTPIN (-2075 2100) $PN BH91
J 2
(-2085 2110);
DISPLAY 0.680851 (-2085 2110);
PAINT MONO (-2085 2110);
FORCEPROP 0 LASTPIN (-2075 2150) $PN BK81
J 2
(-2085 2160);
DISPLAY 0.680851 (-2085 2160);
PAINT MONO (-2085 2160);
FORCEPROP 0 LASTPIN (-2075 2200) $PN BK83
J 2
(-2085 2210);
DISPLAY 0.680851 (-2085 2210);
PAINT MONO (-2085 2210);
FORCEPROP 0 LASTPIN (-2075 2250) $PN BK85
J 2
(-2085 2260);
DISPLAY 0.680851 (-2085 2260);
PAINT MONO (-2085 2260);
FORCEPROP 0 LASTPIN (-2075 2300) $PN BK87
J 2
(-2085 2310);
DISPLAY 0.680851 (-2085 2310);
PAINT MONO (-2085 2310);
FORCEPROP 0 LASTPIN (-2075 2350) $PN BK89
J 2
(-2085 2360);
DISPLAY 0.680851 (-2085 2360);
PAINT MONO (-2085 2360);
FORCEPROP 0 LASTPIN (-2075 2400) $PN BK91
J 2
(-2085 2410);
DISPLAY 0.680851 (-2085 2410);
PAINT MONO (-2085 2410);
FORCEPROP 0 LASTPIN (-2075 2450) $PN BL80
J 2
(-2085 2460);
DISPLAY 0.680851 (-2085 2460);
PAINT MONO (-2085 2460);
FORCEPROP 0 LASTPIN (-2075 2500) $PN BL82
J 2
(-2085 2510);
DISPLAY 0.680851 (-2085 2510);
PAINT MONO (-2085 2510);
FORCEPROP 0 LASTPIN (-2075 2550) $PN BL84
J 2
(-2085 2560);
DISPLAY 0.680851 (-2085 2560);
PAINT MONO (-2085 2560);
FORCEPROP 0 LASTPIN (-2075 2600) $PN BL86
J 2
(-2085 2610);
DISPLAY 0.680851 (-2085 2610);
PAINT MONO (-2085 2610);
FORCEPROP 0 LASTPIN (-2075 2650) $PN BL88
J 2
(-2085 2660);
DISPLAY 0.680851 (-2085 2660);
PAINT MONO (-2085 2660);
FORCEPROP 0 LASTPIN (-2075 2700) $PN BL90
J 2
(-2085 2710);
DISPLAY 0.680851 (-2085 2710);
PAINT MONO (-2085 2710);
FORCEPROP 0 LASTPIN (-2075 2750) $PN BM79
J 2
(-2085 2760);
DISPLAY 0.680851 (-2085 2760);
PAINT MONO (-2085 2760);
FORCEPROP 0 LASTPIN (-2075 2800) $PN BM81
J 2
(-2085 2810);
DISPLAY 0.680851 (-2085 2810);
PAINT MONO (-2085 2810);
FORCEPROP 0 LASTPIN (-2075 2850) $PN BM83
J 2
(-2085 2860);
DISPLAY 0.680851 (-2085 2860);
PAINT MONO (-2085 2860);
FORCEPROP 0 LASTPIN (-2075 2900) $PN BM85
J 2
(-2085 2910);
DISPLAY 0.680851 (-2085 2910);
PAINT MONO (-2085 2910);
FORCEPROP 0 LASTPIN (-2075 2950) $PN BM87
J 2
(-2085 2960);
DISPLAY 0.680851 (-2085 2960);
PAINT MONO (-2085 2960);
FORCEPROP 0 LASTPIN (-2075 3000) $PN BM89
J 2
(-2085 3010);
DISPLAY 0.680851 (-2085 3010);
PAINT MONO (-2085 3010);
FORCEPROP 0 LASTPIN (-2075 3050) $PN BM91
J 2
(-2085 3060);
DISPLAY 0.680851 (-2085 3060);
PAINT MONO (-2085 3060);
FORCEPROP 0 LASTPIN (-2075 3100) $PN BN33
J 2
(-2085 3110);
DISPLAY 0.680851 (-2085 3110);
PAINT MONO (-2085 3110);
FORCEPROP 0 LASTPIN (-2075 3150) $PN BN35
J 2
(-2085 3160);
DISPLAY 0.680851 (-2085 3160);
PAINT MONO (-2085 3160);
FORCEPROP 0 LASTPIN (-2075 3200) $PN BN37
J 2
(-2085 3210);
DISPLAY 0.680851 (-2085 3210);
PAINT MONO (-2085 3210);
FORCEPROP 0 LASTPIN (-2075 3250) $PN BN39
J 2
(-2085 3260);
DISPLAY 0.680851 (-2085 3260);
PAINT MONO (-2085 3260);
FORCEPROP 0 LASTPIN (-2075 3300) $PN BN41
J 2
(-2085 3310);
DISPLAY 0.680851 (-2085 3310);
PAINT MONO (-2085 3310);
FORCEPROP 0 LASTPIN (325 3050) $PN AY18
J 0
(335 3060);
DISPLAY 0.680851 (335 3060);
PAINT MONO (335 3060);
FORCEPROP 0 LASTPIN (325 3300) $PN BA15
J 0
(335 3310);
DISPLAY 0.680851 (335 3310);
PAINT MONO (335 3310);
FORCEPROP 0 LASTPIN (325 2750) $PN BC60
J 0
(335 2760);
DISPLAY 0.680851 (335 2760);
PAINT MONO (335 2760);
FORCEPROP 0 LASTPIN (325 2900) $PN BE15
J 0
(335 2910);
DISPLAY 0.680851 (335 2910);
PAINT MONO (335 2910);
FORCEPROP 0 LASTPIN (325 3250) $PN BE60
J 0
(335 3260);
DISPLAY 0.680851 (335 3260);
PAINT MONO (335 3260);
FORCEPROP 0 LASTPIN (325 2800) $PN BG60
J 0
(335 2810);
DISPLAY 0.680851 (335 2810);
PAINT MONO (335 2810);
FORCEPROP 0 LASTPIN (325 2950) $PN BJ15
J 0
(335 2960);
DISPLAY 0.680851 (335 2960);
PAINT MONO (335 2960);
FORCEPROP 0 LASTPIN (325 2700) $PN BJ60
J 0
(335 2710);
DISPLAY 0.680851 (335 2710);
PAINT MONO (335 2710);
FORCEPROP 0 LASTPIN (325 2850) $PN BK61
J 0
(335 2860);
DISPLAY 0.680851 (335 2860);
PAINT MONO (335 2860);
FORCEPROP 0 LASTPIN (325 3000) $PN BN15
J 0
(335 3010);
DISPLAY 0.680851 (335 3010);
PAINT MONO (335 3010);
FORCEPROP 0 LASTPIN (325 2650) $PN CA15
J 0
(335 2660);
DISPLAY 0.680851 (335 2660);
PAINT MONO (335 2660);
FORCEPROP 0 LASTPIN (325 3200) $PN CE19
J 0
(335 3210);
DISPLAY 0.680851 (335 3210);
PAINT MONO (335 3210);
FORCEPROP 0 LASTPIN (325 2500) $PN CJ11
J 0
(335 2510);
DISPLAY 0.680851 (335 2510);
PAINT MONO (335 2510);
FORCEPROP 0 LASTPIN (325 2550) $PN CJ19
J 0
(335 2560);
DISPLAY 0.680851 (335 2560);
PAINT MONO (335 2560);
FORCEPROP 0 LASTPIN (325 2600) $PN CN19
J 0
(335 2610);
DISPLAY 0.680851 (335 2610);
PAINT MONO (335 2610);
FORCEPROP 0 LASTPIN (325 2350) $PN CP63
J 0
(335 2360);
DISPLAY 0.680851 (335 2360);
PAINT MONO (335 2360);
FORCEPROP 0 LASTPIN (325 2450) $PN CT63
J 0
(335 2460);
DISPLAY 0.680851 (335 2460);
PAINT MONO (335 2460);
FORCEPROP 0 LASTPIN (325 2300) $PN CV61
J 0
(335 2310);
DISPLAY 0.680851 (335 2310);
PAINT MONO (335 2310);
FORCEPROP 0 LASTPIN (325 3150) $PN CV63
J 0
(335 3160);
DISPLAY 0.680851 (335 3160);
PAINT MONO (335 3160);
FORCEPROP 0 LASTPIN (325 2400) $PN CW62
J 0
(335 2410);
DISPLAY 0.680851 (335 2410);
PAINT MONO (335 2410);
FORCEPROP 0 LASTPIN (325 2200) $PN DA21
J 0
(335 2210);
DISPLAY 0.680851 (335 2210);
PAINT MONO (335 2210);
FORCEPROP 2 LAST CDS_LIB pure_quanta
J 0
(-875 2325);
DISPLAY INVISIBLE (-875 2325);
FORCEPROP 1 LAST NEEDS_NO_SIZE TRUE
J 0
(-875 2325);
DISPLAY 0.723404 (-875 2325);
PAINT GREEN (-875 2325);
DISPLAY INVISIBLE (-875 2325);
FORCEPROP 1 LAST CDS_LMAN_SYM_OUTLINE -1050,1150,1050,-1100
J 0
(-875 2325);
DISPLAY 0.468085 (-875 2325);
PAINT GREEN (-875 2325);
DISPLAY INVISIBLE (-875 2325);
FORCEPROP 2 LAST CDS_LOCATION U1
J 0
(-1925 3800);
DISPLAY 1.021277 (-1925 3800);
DISPLAY INVISIBLE (-1925 3800);
FORCEPROP 0 LAST $SEC 28
J 0
(-1925 3800);
DISPLAY 0.680851 (-1925 3800);
PAINT MONO (-1925 3800);
DISPLAY INVISIBLE (-1925 3800);
FORCEPROP 2 LAST CDS_SEC 28
J 0
(-1925 3800);
DISPLAY 1.021277 (-1925 3800);
DISPLAY INVISIBLE (-1925 3800);
FORCEPROP 1 LAST PATH I1
J 0
(-875 2325);
DISPLAY 0.723404 (-875 2325);
PAINT GREEN (-875 2325);
DISPLAY INVISIBLE (-875 2325);
FORCEADD VCC_CORE..1
(2050 3525);
FORCEPROP 3 LASTPIN (2050 3475) SIG_NAME PVCCD_HV_CPU1\g
J 0
(2060 3485);
DISPLAY 0.659574 (2060 3485);
PAINT MONO (2060 3485);
DISPLAY INVISIBLE (2060 3485);
FORCEPROP 1 LAST HDL_POWER PVCCD_HV_CPU1
J 1
(2050 3575);
DISPLAY 1.148936 (2050 3575);
PAINT GREEN (2050 3575);
FORCEPROP 2 LAST CDS_LIB logical_power
J 0
(2050 3525);
PAINT MONO (2050 3525);
DISPLAY INVISIBLE (2050 3525);
FORCEPROP 1 LAST PATH I10
J 0
(2100 3550);
DISPLAY 0.872340 (2100 3550);
PAINT AQUA (2100 3550);
DISPLAY INVISIBLE (2100 3550);
FORCEADD VCC_CORE..1
(5300 875);
FORCEPROP 3 LASTPIN (5300 825) SIG_NAME PVCCFA_EHV_CPU1\g
J 0
(5310 835);
DISPLAY 0.659574 (5310 835);
PAINT MONO (5310 835);
DISPLAY INVISIBLE (5310 835);
FORCEPROP 1 LAST HDL_POWER PVCCFA_EHV_CPU1
J 1
(5300 925);
DISPLAY 1.148936 (5300 925);
PAINT GREEN (5300 925);
FORCEPROP 2 LAST CDS_LIB logical_power
J 0
(5300 875);
PAINT MONO (5300 875);
DISPLAY INVISIBLE (5300 875);
FORCEPROP 1 LAST PATH I11
J 0
(5350 900);
DISPLAY 0.872340 (5350 900);
PAINT AQUA (5350 900);
DISPLAY INVISIBLE (5350 900);
FORCEADD VCC_CORE..1
(5300 1525);
FORCEPROP 3 LASTPIN (5300 1475) SIG_NAME PVNN_MAIN_CPU1\g
J 0
(5310 1485);
DISPLAY 0.659574 (5310 1485);
PAINT MONO (5310 1485);
DISPLAY INVISIBLE (5310 1485);
FORCEPROP 1 LAST HDL_POWER PVNN_MAIN_CPU1
J 1
(5300 1575);
DISPLAY 1.148936 (5300 1575);
PAINT GREEN (5300 1575);
FORCEPROP 2 LAST CDS_LIB logical_power
J 0
(5300 1525);
PAINT MONO (5300 1525);
DISPLAY INVISIBLE (5300 1525);
FORCEPROP 1 LAST PATH I12
J 0
(5350 1550);
DISPLAY 0.872340 (5350 1550);
PAINT AQUA (5350 1550);
DISPLAY INVISIBLE (5350 1550);
FORCEADD VCC_CORE..1
(4950 3975);
FORCEPROP 3 LASTPIN (4950 3925) SIG_NAME PVCCINFAON_CPU1\g
J 0
(4960 3935);
DISPLAY 0.659574 (4960 3935);
PAINT MONO (4960 3935);
DISPLAY INVISIBLE (4960 3935);
FORCEPROP 1 LAST HDL_POWER PVCCINFAON_CPU1
J 1
(4950 4025);
DISPLAY 1.148936 (4950 4025);
PAINT GREEN (4950 4025);
FORCEPROP 2 LAST CDS_LIB logical_power
J 0
(4950 3975);
PAINT MONO (4950 3975);
DISPLAY INVISIBLE (4950 3975);
FORCEPROP 1 LAST PATH I13
J 0
(5000 4000);
DISPLAY 0.872340 (5000 4000);
PAINT AQUA (5000 4000);
DISPLAY INVISIBLE (5000 4000);
FORCEADD VCC_CORE..1
(-2325 3525);
FORCEPROP 3 LASTPIN (-2325 3475) SIG_NAME PVCCIN_CPU1\g
J 0
(-2315 3485);
DISPLAY 0.659574 (-2315 3485);
PAINT MONO (-2315 3485);
DISPLAY INVISIBLE (-2315 3485);
FORCEPROP 1 LAST HDL_POWER PVCCIN_CPU1
J 1
(-2325 3575);
DISPLAY 1.148936 (-2325 3575);
PAINT GREEN (-2325 3575);
FORCEPROP 2 LAST CDS_LIB logical_power
J 0
(-2325 3525);
PAINT MONO (-2325 3525);
DISPLAY INVISIBLE (-2325 3525);
FORCEPROP 1 LAST PATH I2
J 0
(-2275 3550);
DISPLAY 0.872340 (-2275 3550);
PAINT AQUA (-2275 3550);
DISPLAY INVISIBLE (-2275 3550);
FORCEADD VCC_CORE..1
(575 3525);
FORCEPROP 3 LASTPIN (575 3475) SIG_NAME PVCCINFAON_CPU1\g
J 0
(585 3485);
DISPLAY 0.659574 (585 3485);
PAINT MONO (585 3485);
DISPLAY INVISIBLE (585 3485);
FORCEPROP 1 LAST HDL_POWER PVCCINFAON_CPU1
J 1
(575 3575);
DISPLAY 1.148936 (575 3575);
PAINT GREEN (575 3575);
FORCEPROP 2 LAST CDS_LIB logical_power
J 0
(575 3525);
PAINT MONO (575 3525);
DISPLAY INVISIBLE (575 3525);
FORCEPROP 1 LAST PATH I3
J 0
(625 3550);
DISPLAY 0.872340 (625 3550);
PAINT AQUA (625 3550);
DISPLAY INVISIBLE (625 3550);
FORCEADD Q_CAP..1
(1350 1075);
FORCEPROP 1 LAST PART_NUMBER CH6101MEB01
J 0
(1400 925);
DISPLAY 0.978723 (1400 925);
DISPLAY INVISIBLE (1400 925);
FORCEPROP 1 LAST TOLERANCE 20%
J 0
(1400 1025);
DISPLAY 0.978723 (1400 1025);
FORCEPROP 1 LAST VALUE 10UF
J 0
(1400 1125);
DISPLAY 0.978723 (1400 1125);
FORCEPROP 1 LAST MATERIAL X6S
J 0
(1400 975);
DISPLAY 0.978723 (1400 975);
FORCEPROP 1 LAST VOLTAGE 6.3V
J 0
(1400 1075);
DISPLAY 0.978723 (1400 1075);
FORCEPROP 1 LAST PACK_TYPE C0402
J 0
(1400 875);
DISPLAY 0.978723 (1400 875);
FORCEPROP 1 LAST $LOCATION C71
J 0
(1400 1175);
DISPLAY 0.978723 (1400 1175);
FORCEPROP 2 LAST CDS_LIB pure_quanta
J 0
(1350 1075);
PAINT MONO (1350 1075);
DISPLAY INVISIBLE (1350 1075);
FORCEPROP 2 LAST CDS_LOCATION C71
J 0
(1400 1275);
DISPLAY 1.021277 (1400 1275);
DISPLAY INVISIBLE (1400 1275);
FORCEPROP 2 LAST $SEC 1
J 0
(1400 1275);
DISPLAY 0.680851 (1400 1275);
PAINT MONO (1400 1275);
DISPLAY INVISIBLE (1400 1275);
FORCEPROP 2 LAST CDS_SEC 1
J 0
(1400 1275);
DISPLAY 1.021277 (1400 1275);
DISPLAY INVISIBLE (1400 1275);
FORCEPROP 1 LASTPIN (1350 1175) $PN 1
J 0
(1360 1155);
DISPLAY 0.787234 (1360 1155);
DISPLAY INVISIBLE (1360 1155);
FORCEPROP 1 LASTPIN (1350 975) $PN 2
J 0
(1360 955);
DISPLAY 0.787234 (1360 955);
DISPLAY INVISIBLE (1360 955);
FORCEPROP 1 LAST PATH I4
J 0
(1400 1225);
DISPLAY 0.978723 (1400 1225);
PAINT WHITE (1400 1225);
DISPLAY INVISIBLE (1400 1225);
FORCEADD UNIVERSAL_GND..1
(1350 800);
FORCEPROP 3 LASTPIN (1350 850) SIG_NAME GND\g
J 0
(1360 860);
DISPLAY 0.659574 (1360 860);
PAINT MONO (1360 860);
DISPLAY INVISIBLE (1360 860);
FORCEPROP 2 LAST CDS_LIB logical_power
J 0
(1350 800);
PAINT MONO (1350 800);
DISPLAY INVISIBLE (1350 800);
FORCEPROP 1 LAST HDL_POWER GND
J 1
(1375 725);
DISPLAY 0.872340 (1375 725);
PAINT GREEN (1375 725);
DISPLAY INVISIBLE (1375 725);
FORCEPROP 1 LAST PATH I5
J 0
(1425 800);
DISPLAY 0.872340 (1425 800);
PAINT AQUA (1425 800);
DISPLAY INVISIBLE (1425 800);
FORCEADD VCC_CORE..1
(1350 1425);
FORCEPROP 3 LASTPIN (1350 1375) SIG_NAME P3V3_AUX\g
J 0
(1360 1385);
DISPLAY 0.659574 (1360 1385);
PAINT MONO (1360 1385);
DISPLAY INVISIBLE (1360 1385);
FORCEPROP 1 LAST HDL_POWER P3V3_AUX
J 1
(1350 1475);
DISPLAY 1.148936 (1350 1475);
PAINT GREEN (1350 1475);
FORCEPROP 2 LAST CDS_LIB logical_power
J 0
(1350 1425);
PAINT MONO (1350 1425);
DISPLAY INVISIBLE (1350 1425);
FORCEPROP 1 LAST PATH I6
J 0
(1400 1450);
DISPLAY 0.872340 (1400 1450);
PAINT AQUA (1400 1450);
DISPLAY INVISIBLE (1400 1450);
FORCEADD VCC_CORE..1
(2050 1100);
FORCEPROP 3 LASTPIN (2050 1050) SIG_NAME PVPP_HBM_CPU1\g
J 0
(2060 1060);
DISPLAY 0.659574 (2060 1060);
PAINT MONO (2060 1060);
DISPLAY INVISIBLE (2060 1060);
FORCEPROP 1 LAST HDL_POWER PVPP_HBM_CPU1
J 1
(2050 1150);
DISPLAY 1.148936 (2050 1150);
PAINT GREEN (2050 1150);
FORCEPROP 2 LAST CDS_LIB logical_power
J 0
(2050 1100);
PAINT MONO (2050 1100);
DISPLAY INVISIBLE (2050 1100);
FORCEPROP 1 LAST PATH I7
J 0
(2100 1125);
DISPLAY 0.872340 (2100 1125);
PAINT AQUA (2100 1125);
DISPLAY INVISIBLE (2100 1125);
FORCEADD SOCKET4677_AZIF0045P001C01CS..29
(3500 1925);
FORCEPROP 1 LAST PART_NUMBER DGA^7000023
J 0
(2450 3825);
DISPLAY 0.723404 (2450 3825);
PAINT GREEN (2450 3825);
DISPLAY INVISIBLE (2450 3825);
FORCEPROP 2 LAST PART_TYPE SMLF
J 0
(2450 4000);
DISPLAY 1.021277 (2450 4000);
FORCEPROP 1 LAST MATERIAL IO
J 0
(2450 3750);
DISPLAY 0.723404 (2450 3750);
PAINT GREEN (2450 3750);
FORCEPROP 2 LAST VALUE SOCKET4677_AZIF0045-P001C01CS
J 0
(2450 3950);
DISPLAY 1.021277 (2450 3950);
FORCEPROP 1 LAST $LOCATION U1
J 0
(2450 3900);
DISPLAY 0.723404 (2450 3900);
PAINT GREEN (2450 3900);
FORCEPROP 0 LASTPIN (2300 1900) $PN AT36
J 2
(2290 1910);
DISPLAY 0.680851 (2290 1910);
PAINT MONO (2290 1910);
FORCEPROP 0 LASTPIN (2300 1950) $PN AT55
J 2
(2290 1960);
DISPLAY 0.680851 (2290 1960);
PAINT MONO (2290 1960);
FORCEPROP 0 LASTPIN (2300 2000) $PN AU3
J 2
(2290 2010);
DISPLAY 0.680851 (2290 2010);
PAINT MONO (2290 2010);
FORCEPROP 0 LASTPIN (2300 2100) $PN AU35
J 2
(2290 2110);
DISPLAY 0.680851 (2290 2110);
PAINT MONO (2290 2110);
FORCEPROP 0 LASTPIN (2300 2150) $PN AU54
J 2
(2290 2160);
DISPLAY 0.680851 (2290 2160);
PAINT MONO (2290 2160);
FORCEPROP 0 LASTPIN (2300 2050) $PN AU7
J 2
(2290 2060);
DISPLAY 0.680851 (2290 2060);
PAINT MONO (2290 2060);
FORCEPROP 0 LASTPIN (2300 2200) $PN AV34
J 2
(2290 2210);
DISPLAY 0.680851 (2290 2210);
PAINT MONO (2290 2210);
FORCEPROP 0 LASTPIN (2300 2250) $PN AV36
J 2
(2290 2260);
DISPLAY 0.680851 (2290 2260);
PAINT MONO (2290 2260);
FORCEPROP 0 LASTPIN (2300 2300) $PN AV53
J 2
(2290 2310);
DISPLAY 0.680851 (2290 2310);
PAINT MONO (2290 2310);
FORCEPROP 0 LASTPIN (2300 2350) $PN AV55
J 2
(2290 2360);
DISPLAY 0.680851 (2290 2360);
PAINT MONO (2290 2360);
FORCEPROP 0 LASTPIN (2300 2400) $PN BA3
J 2
(2290 2410);
DISPLAY 0.680851 (2290 2410);
PAINT MONO (2290 2410);
FORCEPROP 0 LASTPIN (2300 2450) $PN BA7
J 2
(2290 2460);
DISPLAY 0.680851 (2290 2460);
PAINT MONO (2290 2460);
FORCEPROP 0 LASTPIN (2300 2600) $PN BE11
J 2
(2290 2610);
DISPLAY 0.680851 (2290 2610);
PAINT MONO (2290 2610);
FORCEPROP 0 LASTPIN (2300 2500) $PN BE3
J 2
(2290 2510);
DISPLAY 0.680851 (2290 2510);
PAINT MONO (2290 2510);
FORCEPROP 0 LASTPIN (2300 2550) $PN BE7
J 2
(2290 2560);
DISPLAY 0.680851 (2290 2560);
PAINT MONO (2290 2560);
FORCEPROP 0 LASTPIN (2300 2750) $PN BJ11
J 2
(2290 2760);
DISPLAY 0.680851 (2290 2760);
PAINT MONO (2290 2760);
FORCEPROP 0 LASTPIN (2300 2650) $PN BJ3
J 2
(2290 2660);
DISPLAY 0.680851 (2290 2660);
PAINT MONO (2290 2660);
FORCEPROP 0 LASTPIN (2300 2700) $PN BJ7
J 2
(2290 2710);
DISPLAY 0.680851 (2290 2710);
PAINT MONO (2290 2710);
FORCEPROP 0 LASTPIN (2300 2800) $PN BN7
J 2
(2290 2810);
DISPLAY 0.680851 (2290 2810);
PAINT MONO (2290 2810);
FORCEPROP 0 LASTPIN (2300 2850) $PN CA7
J 2
(2290 2860);
DISPLAY 0.680851 (2290 2860);
PAINT MONO (2290 2860);
FORCEPROP 0 LASTPIN (2300 2900) $PN CE7
J 2
(2290 2910);
DISPLAY 0.680851 (2290 2910);
PAINT MONO (2290 2910);
FORCEPROP 0 LASTPIN (2300 2950) $PN CW35
J 2
(2290 2960);
DISPLAY 0.680851 (2290 2960);
PAINT MONO (2290 2960);
FORCEPROP 0 LASTPIN (2300 3000) $PN CW37
J 2
(2290 3010);
DISPLAY 0.680851 (2290 3010);
PAINT MONO (2290 3010);
FORCEPROP 0 LASTPIN (2300 3050) $PN CW52
J 2
(2290 3060);
DISPLAY 0.680851 (2290 3060);
PAINT MONO (2290 3060);
FORCEPROP 0 LASTPIN (2300 3100) $PN CW54
J 2
(2290 3110);
DISPLAY 0.680851 (2290 3110);
PAINT MONO (2290 3110);
FORCEPROP 0 LASTPIN (2300 3150) $PN CW56
J 2
(2290 3160);
DISPLAY 0.680851 (2290 3160);
PAINT MONO (2290 3160);
FORCEPROP 0 LASTPIN (2300 3200) $PN CY34
J 2
(2290 3210);
DISPLAY 0.680851 (2290 3210);
PAINT MONO (2290 3210);
FORCEPROP 0 LASTPIN (2300 3250) $PN CY36
J 2
(2290 3260);
DISPLAY 0.680851 (2290 3260);
PAINT MONO (2290 3260);
FORCEPROP 0 LASTPIN (2300 3300) $PN CY53
J 2
(2290 3310);
DISPLAY 0.680851 (2290 3310);
PAINT MONO (2290 3310);
FORCEPROP 0 LASTPIN (4700 400) $PN AA3
J 0
(4710 410);
DISPLAY 0.680851 (4710 410);
PAINT MONO (4710 410);
FORCEPROP 0 LASTPIN (4700 450) $PN AE3
J 0
(4710 460);
DISPLAY 0.680851 (4710 460);
PAINT MONO (4710 460);
FORCEPROP 0 LASTPIN (4700 500) $PN AJ3
J 0
(4710 510);
DISPLAY 0.680851 (4710 510);
PAINT MONO (4710 510);
FORCEPROP 0 LASTPIN (4700 550) $PN AN3
J 0
(4710 560);
DISPLAY 0.680851 (4710 560);
PAINT MONO (4710 560);
FORCEPROP 0 LASTPIN (4700 600) $PN AT61
J 0
(4710 610);
DISPLAY 0.680851 (4710 610);
PAINT MONO (4710 610);
FORCEPROP 0 LASTPIN (4700 650) $PN AU60
J 0
(4710 660);
DISPLAY 0.680851 (4710 660);
PAINT MONO (4710 660);
FORCEPROP 0 LASTPIN (4700 700) $PN AV61
J 0
(4710 710);
DISPLAY 0.680851 (4710 710);
PAINT MONO (4710 710);
FORCEPROP 0 LASTPIN (4700 750) $PN AW60
J 0
(4710 760);
DISPLAY 0.680851 (4710 760);
PAINT MONO (4710 760);
FORCEPROP 0 LASTPIN (4700 300) $PN N3
J 0
(4710 310);
DISPLAY 0.680851 (4710 310);
PAINT MONO (4710 310);
FORCEPROP 0 LASTPIN (4700 350) $PN U3
J 0
(4710 360);
DISPLAY 0.680851 (4710 360);
PAINT MONO (4710 360);
FORCEPROP 0 LASTPIN (4700 1650) $PN CE15
J 0
(4710 1660);
DISPLAY 0.680851 (4710 1660);
PAINT MONO (4710 1660);
FORCEPROP 0 LASTPIN (4700 1800) $PN CJ15
J 0
(4710 1810);
DISPLAY 0.680851 (4710 1810);
PAINT MONO (4710 1810);
FORCEPROP 0 LASTPIN (4700 1700) $PN CJ3
J 0
(4710 1710);
DISPLAY 0.680851 (4710 1710);
PAINT MONO (4710 1710);
FORCEPROP 0 LASTPIN (4700 1750) $PN CJ7
J 0
(4710 1760);
DISPLAY 0.680851 (4710 1760);
PAINT MONO (4710 1760);
FORCEPROP 0 LASTPIN (4700 1950) $PN CN11
J 0
(4710 1960);
DISPLAY 0.680851 (4710 1960);
PAINT MONO (4710 1960);
FORCEPROP 0 LASTPIN (4700 2000) $PN CN15
J 0
(4710 2010);
DISPLAY 0.680851 (4710 2010);
PAINT MONO (4710 2010);
FORCEPROP 0 LASTPIN (4700 1850) $PN CN3
J 0
(4710 1860);
DISPLAY 0.680851 (4710 1860);
PAINT MONO (4710 1860);
FORCEPROP 0 LASTPIN (4700 2050) $PN CN64
J 0
(4710 2060);
DISPLAY 0.680851 (4710 2060);
PAINT MONO (4710 2060);
FORCEPROP 0 LASTPIN (4700 2100) $PN CN66
J 0
(4710 2110);
DISPLAY 0.680851 (4710 2110);
PAINT MONO (4710 2110);
FORCEPROP 0 LASTPIN (4700 1900) $PN CN7
J 0
(4710 1910);
DISPLAY 0.680851 (4710 1910);
PAINT MONO (4710 1910);
FORCEPROP 0 LASTPIN (4700 2150) $PN CP65
J 0
(4710 2160);
DISPLAY 0.680851 (4710 2160);
PAINT MONO (4710 2160);
FORCEPROP 0 LASTPIN (4700 2200) $PN CP67
J 0
(4710 2210);
DISPLAY 0.680851 (4710 2210);
PAINT MONO (4710 2210);
FORCEPROP 0 LASTPIN (4700 2300) $PN CT65
J 0
(4710 2310);
DISPLAY 0.680851 (4710 2310);
PAINT MONO (4710 2310);
FORCEPROP 0 LASTPIN (4700 2350) $PN CT67
J 0
(4710 2360);
DISPLAY 0.680851 (4710 2360);
PAINT MONO (4710 2360);
FORCEPROP 0 LASTPIN (4700 2500) $PN CU11
J 0
(4710 2510);
DISPLAY 0.680851 (4710 2510);
PAINT MONO (4710 2510);
FORCEPROP 0 LASTPIN (4700 2550) $PN CU15
J 0
(4710 2560);
DISPLAY 0.680851 (4710 2560);
PAINT MONO (4710 2560);
FORCEPROP 0 LASTPIN (4700 2400) $PN CU3
J 0
(4710 2410);
DISPLAY 0.680851 (4710 2410);
PAINT MONO (4710 2410);
FORCEPROP 0 LASTPIN (4700 2600) $PN CU64
J 0
(4710 2610);
DISPLAY 0.680851 (4710 2610);
PAINT MONO (4710 2610);
FORCEPROP 0 LASTPIN (4700 2450) $PN CU7
J 0
(4710 2460);
DISPLAY 0.680851 (4710 2460);
PAINT MONO (4710 2460);
FORCEPROP 0 LASTPIN (4700 2650) $PN CV65
J 0
(4710 2660);
DISPLAY 0.680851 (4710 2660);
PAINT MONO (4710 2660);
FORCEPROP 0 LASTPIN (4700 2700) $PN CV67
J 0
(4710 2710);
DISPLAY 0.680851 (4710 2710);
PAINT MONO (4710 2710);
FORCEPROP 0 LASTPIN (4700 2800) $PN CW66
J 0
(4710 2810);
DISPLAY 0.680851 (4710 2810);
PAINT MONO (4710 2810);
FORCEPROP 0 LASTPIN (4700 2850) $PN CY65
J 0
(4710 2860);
DISPLAY 0.680851 (4710 2860);
PAINT MONO (4710 2860);
FORCEPROP 0 LASTPIN (4700 2900) $PN CY67
J 0
(4710 2910);
DISPLAY 0.680851 (4710 2910);
PAINT MONO (4710 2910);
FORCEPROP 0 LASTPIN (4700 3050) $PN DA11
J 0
(4710 3060);
DISPLAY 0.680851 (4710 3060);
PAINT MONO (4710 3060);
FORCEPROP 0 LASTPIN (4700 3100) $PN DA15
J 0
(4710 3110);
DISPLAY 0.680851 (4710 3110);
PAINT MONO (4710 3110);
FORCEPROP 0 LASTPIN (4700 3150) $PN DA64
J 0
(4710 3160);
DISPLAY 0.680851 (4710 3160);
PAINT MONO (4710 3160);
FORCEPROP 0 LASTPIN (4700 3300) $PN DE11
J 0
(4710 3310);
DISPLAY 0.680851 (4710 3310);
PAINT MONO (4710 3310);
FORCEPROP 0 LASTPIN (4700 3350) $PN DE15
J 0
(4710 3360);
DISPLAY 0.680851 (4710 3360);
PAINT MONO (4710 3360);
FORCEPROP 0 LASTPIN (4700 3200) $PN DE3
J 0
(4710 3210);
DISPLAY 0.680851 (4710 3210);
PAINT MONO (4710 3210);
FORCEPROP 0 LASTPIN (4700 3550) $PN DJ15
J 0
(4710 3560);
DISPLAY 0.680851 (4710 3560);
PAINT MONO (4710 3560);
FORCEPROP 0 LASTPIN (4700 3400) $PN DJ3
J 0
(4710 3410);
DISPLAY 0.680851 (4710 3410);
PAINT MONO (4710 3410);
FORCEPROP 0 LASTPIN (4700 3450) $PN DJ7
J 0
(4710 3460);
DISPLAY 0.680851 (4710 3460);
PAINT MONO (4710 3460);
FORCEPROP 0 LASTPIN (4700 2250) $PN CR66
J 0
(4710 2260);
DISPLAY 0.680851 (4710 2260);
PAINT MONO (4710 2260);
FORCEPROP 0 LASTPIN (4700 2750) $PN CW64
J 0
(4710 2760);
DISPLAY 0.680851 (4710 2760);
PAINT MONO (4710 2760);
FORCEPROP 0 LASTPIN (4700 2950) $PN DA3
J 0
(4710 2960);
DISPLAY 0.680851 (4710 2960);
PAINT MONO (4710 2960);
FORCEPROP 0 LASTPIN (4700 3000) $PN DA7
J 0
(4710 3010);
DISPLAY 0.680851 (4710 3010);
PAINT MONO (4710 3010);
FORCEPROP 0 LASTPIN (4700 3250) $PN DE7
J 0
(4710 3260);
DISPLAY 0.680851 (4710 3260);
PAINT MONO (4710 3260);
FORCEPROP 0 LASTPIN (4700 3500) $PN DJ11
J 0
(4710 3510);
DISPLAY 0.680851 (4710 3510);
PAINT MONO (4710 3510);
FORCEPROP 0 LASTPIN (2300 1500) $PN BA19
J 2
(2290 1510);
DISPLAY 0.680851 (2290 1510);
PAINT MONO (2290 1510);
FORCEPROP 0 LASTPIN (2300 1550) $PN BE19
J 2
(2290 1560);
DISPLAY 0.680851 (2290 1560);
PAINT MONO (2290 1560);
FORCEPROP 0 LASTPIN (4700 1400) $PN BJ19
J 0
(4710 1410);
DISPLAY 0.680851 (4710 1410);
PAINT MONO (4710 1410);
FORCEPROP 0 LASTPIN (4700 1450) $PN BN19
J 0
(4710 1460);
DISPLAY 0.680851 (4710 1460);
PAINT MONO (4710 1460);
FORCEPROP 0 LASTPIN (2300 950) $PN CF67
J 2
(2290 960);
DISPLAY 0.680851 (2290 960);
PAINT MONO (2290 960);
FORCEPROP 0 LASTPIN (2300 900) $PN CE68
J 2
(2290 910);
DISPLAY 0.680851 (2290 910);
PAINT MONO (2290 910);
FORCEPROP 0 LASTPIN (2300 850) $PN CD67
J 2
(2290 860);
DISPLAY 0.680851 (2290 860);
PAINT MONO (2290 860);
FORCEPROP 0 LASTPIN (2300 800) $PN CC68
J 2
(2290 810);
DISPLAY 0.680851 (2290 810);
PAINT MONO (2290 810);
FORCEPROP 0 LASTPIN (2300 1300) $PN BC21
J 2
(2290 1310);
DISPLAY 0.680851 (2290 1310);
PAINT MONO (2290 1310);
FORCEPROP 0 LASTPIN (2300 1250) $PN BA21
J 2
(2290 1260);
DISPLAY 0.680851 (2290 1260);
PAINT MONO (2290 1260);
FORCEPROP 0 LASTPIN (2300 1000) $PN CG68
J 2
(2290 1010);
DISPLAY 0.680851 (2290 1010);
PAINT MONO (2290 1010);
FORCEPROP 2 LAST CDS_LIB pure_quanta
J 0
(3500 1925);
DISPLAY INVISIBLE (3500 1925);
FORCEPROP 1 LAST NEEDS_NO_SIZE TRUE
J 0
(3500 1925);
DISPLAY 0.723404 (3500 1925);
PAINT GREEN (3500 1925);
DISPLAY INVISIBLE (3500 1925);
FORCEPROP 1 LAST CDS_LMAN_SYM_OUTLINE -1050,1800,1050,-1750
J 0
(3500 1925);
DISPLAY 0.468085 (3500 1925);
PAINT GREEN (3500 1925);
DISPLAY INVISIBLE (3500 1925);
FORCEPROP 2 LAST CDS_LOCATION U1
J 0
(2450 4050);
DISPLAY 1.021277 (2450 4050);
DISPLAY INVISIBLE (2450 4050);
FORCEPROP 0 LAST $SEC 29
J 0
(2450 4050);
DISPLAY 0.680851 (2450 4050);
PAINT MONO (2450 4050);
DISPLAY INVISIBLE (2450 4050);
FORCEPROP 2 LAST CDS_SEC 29
J 0
(2450 4050);
DISPLAY 1.021277 (2450 4050);
DISPLAY INVISIBLE (2450 4050);
FORCEPROP 1 LAST PATH I8
J 0
(3500 1925);
DISPLAY 0.723404 (3500 1925);
PAINT GREEN (3500 1925);
DISPLAY INVISIBLE (3500 1925);
FORCEADD VCC_CORE..1
(2050 1675);
FORCEPROP 3 LASTPIN (2050 1625) SIG_NAME PVNN_MAIN_CPU1\g
J 0
(2060 1635);
DISPLAY 0.659574 (2060 1635);
PAINT MONO (2060 1635);
DISPLAY INVISIBLE (2060 1635);
FORCEPROP 1 LAST HDL_POWER PVNN_MAIN_CPU1
J 1
(2050 1725);
DISPLAY 1.148936 (2050 1725);
PAINT GREEN (2050 1725);
FORCEPROP 2 LAST CDS_LIB logical_power
J 0
(2050 1675);
PAINT MONO (2050 1675);
DISPLAY INVISIBLE (2050 1675);
FORCEPROP 1 LAST PATH I9
J 0
(2100 1700);
DISPLAY 0.872340 (2100 1700);
PAINT AQUA (2100 1700);
DISPLAY INVISIBLE (2100 1700);
FORCEADD QUANTA_TITLE_BLOCK_C..1
(6125 -1725);
FORCEPROP 0 LAST CDS_CON_LAST_MODIFIED Fri Aug 25 14:00:49 2023
J 0
(4240 -1710);
PAINT MONO (4240 -1710);
DISPLAY INVISIBLE (4240 -1710);
FORCEPROP 2 LAST CUSTOM_TXT_CDS <XR_PAGE_TITLE>
J 0
(-1765 3525);
DISPLAY 0.638298 (-1765 3525);
PAINT PINK (-1765 3525);
DISPLAY INVISIBLE (-1765 3525);
FORCEPROP 2 LAST CUSTOM_TXT_CDS <Q_NUMBER>
J 0
(4722 -1622);
DISPLAY 1.212766 (4722 -1622);
FORCEPROP 2 LAST CUSTOM_TXT_CDS <CON_LAST_MODIFIED>
J 0
(4240 -1710);
DISPLAY 0.978723 (4240 -1710);
FORCEPROP 2 LAST CUSTOM_TXT_CDS <CON_PAGE_NUM> OF <CON_TOTAL_PAGES>
J 0
(5679 -1707);
DISPLAY 0.978723 (5679 -1707);
FORCEPROP 2 LAST CUSTOM_TXT_CDS <Q_PROJ>
J 0
(3743 -1623);
DISPLAY 1.212766 (3743 -1623);
FORCEPROP 2 LAST CUSTOM_TXT_CDS <Q_REV>
J 0
(5941 -1622);
DISPLAY 1.212766 (5941 -1622);
FORCEPROP 1 LAST CUSTOM_TXT_CDS <NAME_2>
J 0
(2950 -1675);
FORCEPROP 1 LAST CUSTOM_TXT_CDS <NAME_1>
J 0
(2950 -1550);
FORCEPROP 1 LAST Q_TITLE SPR CPU1 POWER - VCCIN/VCCINFAON (25)
J 0
(-3241 -1724);
DISPLAY 1.957447 (-3241 -1724);
PAINT GREEN (-3241 -1724);
FORCEPROP 1 LAST Q_DEPT 
J 1
(2362 -1676);
DISPLAY 1.957447 (2362 -1676);
PAINT GREEN (2362 -1676);
FORCEPROP 1 LAST COMMENT_BODY TRUE
J 0
(6137 -1738);
DISPLAY 0.978723 (6137 -1738);
PAINT GREEN (6137 -1738);
DISPLAY INVISIBLE (6137 -1738);
FORCEPROP 2 LAST CDS_XR_PAGE_TITLE CR-68 : @S9S_MB_2U_LIB.S9S_MB_2U(SCH_1):PAGE68
J 0
(-1765 3525);
DISPLAY 0.638298 (-1765 3525);
PAINT PINK (-1765 3525);
DISPLAY INVISIBLE (-1765 3525);
FORCEPROP 2 LAST CDS_LIB pure_quanta
J 0
(6125 -1725);
PAINT MONO (6125 -1725);
DISPLAY INVISIBLE (6125 -1725);
FORCEPROP 1 LAST CDS_LMAN_SYM_OUTLINE -9475,6775,100,-125
J 0
(6125 -1725);
DISPLAY 0.468085 (6125 -1725);
PAINT GREEN (6125 -1725);
DISPLAY INVISIBLE (6125 -1725);
FORCEPROP 2 LAST PAGE_BORDER TRUE
J 0
(-1765 3525);
DISPLAY 0.638298 (-1765 3525);
PAINT PINK (-1765 3525);
DISPLAY INVISIBLE (-1765 3525);
WIRE 16 -1 (-2325 3475)(-2325 3300);
WIRE 16 -1 (575 3475)(575 3300);
WIRE 16 -1 (2050 3475)(2050 3300);
WIRE 16 -1 (2050 1625)(2050 1550);
WIRE 16 -1 (2050 1050)(2050 1000);
WIRE 16 -1 (1350 1375)(1350 1300);
WIRE 16 -1 (4950 3925)(4950 3550);
WIRE 16 -1 (5300 1475)(5300 1400);
WIRE 16 -1 (5300 825)(5300 750);
WIRE 16 -1 (1350 850)(1350 975);
WIRE 16 -1 (575 3300)(325 3300);
WIRE 16 -1 (575 3250)(325 3250);
WIRE 16 -1 (575 3300)(575 3250);
WIRE 16 -1 (575 3200)(325 3200);
WIRE 16 -1 (575 3250)(575 3200);
WIRE 16 -1 (575 3150)(325 3150);
WIRE 16 -1 (575 3200)(575 3150);
WIRE 16 -1 (575 3050)(325 3050);
WIRE 16 -1 (575 3050)(575 3150);
WIRE 16 -1 (575 3000)(325 3000);
WIRE 16 -1 (575 3050)(575 3000);
WIRE 16 -1 (575 2950)(325 2950);
WIRE 16 -1 (575 3000)(575 2950);
WIRE 16 -1 (575 2900)(325 2900);
WIRE 16 -1 (575 2950)(575 2900);
WIRE 16 -1 (575 2850)(325 2850);
WIRE 16 -1 (575 2900)(575 2850);
WIRE 16 -1 (575 2800)(325 2800);
WIRE 16 -1 (575 2850)(575 2800);
WIRE 16 -1 (575 2750)(325 2750);
WIRE 16 -1 (575 2800)(575 2750);
WIRE 16 -1 (575 2700)(325 2700);
WIRE 16 -1 (575 2750)(575 2700);
WIRE 16 -1 (575 2650)(325 2650);
WIRE 16 -1 (575 2700)(575 2650);
WIRE 16 -1 (325 2600)(575 2600);
WIRE 16 -1 (575 2650)(575 2600);
WIRE 16 -1 (325 2550)(575 2550);
WIRE 16 -1 (575 2600)(575 2550);
WIRE 16 -1 (325 2500)(575 2500);
WIRE 16 -1 (575 2550)(575 2500);
WIRE 16 -1 (325 2450)(575 2450);
WIRE 16 -1 (575 2500)(575 2450);
WIRE 16 -1 (325 2400)(575 2400);
WIRE 16 -1 (575 2450)(575 2400);
WIRE 16 -1 (325 2350)(575 2350);
WIRE 16 -1 (575 2400)(575 2350);
WIRE 16 -1 (325 2300)(575 2300);
WIRE 16 -1 (575 2350)(575 2300);
WIRE 16 -1 (575 2200)(575 2300);
WIRE 16 -1 (325 2200)(575 2200);
WIRE 16 -1 (-2075 3300)(-2325 3300);
WIRE 16 -1 (-2325 3300)(-2325 3250);
WIRE 16 -1 (-2075 3250)(-2325 3250);
WIRE 16 -1 (-2325 3250)(-2325 3200);
WIRE 16 -1 (-2075 3200)(-2325 3200);
WIRE 16 -1 (-2325 3200)(-2325 3150);
WIRE 16 -1 (-2075 3150)(-2325 3150);
WIRE 16 -1 (-2325 3150)(-2325 3100);
WIRE 16 -1 (-2075 3100)(-2325 3100);
WIRE 16 -1 (-2075 3050)(-2325 3050);
WIRE 16 -1 (-2325 3100)(-2325 3050);
WIRE 16 -1 (-2325 3050)(-2325 3000);
WIRE 16 -1 (-2075 3000)(-2325 3000);
WIRE 16 -1 (-2325 3000)(-2325 2950);
WIRE 16 -1 (-2075 2950)(-2325 2950);
WIRE 16 -1 (-2325 2950)(-2325 2900);
WIRE 16 -1 (-2075 2900)(-2325 2900);
WIRE 16 -1 (-2325 2900)(-2325 2850);
WIRE 16 -1 (-2075 2850)(-2325 2850);
WIRE 16 -1 (-2325 2850)(-2325 2800);
WIRE 16 -1 (-2075 2800)(-2325 2800);
WIRE 16 -1 (-2325 2800)(-2325 2750);
WIRE 16 -1 (-2075 2750)(-2325 2750);
WIRE 16 -1 (-2325 2750)(-2325 2700);
WIRE 16 -1 (-2075 2700)(-2325 2700);
WIRE 16 -1 (-2325 2700)(-2325 2650);
WIRE 16 -1 (-2075 2650)(-2325 2650);
WIRE 16 -1 (-2325 2650)(-2325 2600);
WIRE 16 -1 (-2325 2600)(-2075 2600);
WIRE 16 -1 (-2325 2550)(-2075 2550);
WIRE 16 -1 (-2325 2600)(-2325 2550);
WIRE 16 -1 (-2325 2550)(-2325 2500);
WIRE 16 -1 (-2325 2500)(-2075 2500);
WIRE 16 -1 (-2325 2500)(-2325 2450);
WIRE 16 -1 (-2325 2450)(-2075 2450);
WIRE 16 -1 (-2325 2450)(-2325 2400);
WIRE 16 -1 (-2325 2400)(-2075 2400);
WIRE 16 -1 (-2325 2400)(-2325 2350);
WIRE 16 -1 (-2325 2350)(-2075 2350);
WIRE 16 -1 (-2325 2350)(-2325 2300);
WIRE 16 -1 (-2325 2300)(-2075 2300);
WIRE 16 -1 (-2325 2300)(-2325 2250);
WIRE 16 -1 (-2325 2250)(-2075 2250);
WIRE 16 -1 (-2325 2250)(-2325 2200);
WIRE 16 -1 (-2325 2200)(-2075 2200);
WIRE 16 -1 (-2325 2200)(-2325 2150);
WIRE 16 -1 (-2325 2150)(-2075 2150);
WIRE 16 -1 (-2325 2150)(-2325 2100);
WIRE 16 -1 (-2325 2100)(-2075 2100);
WIRE 16 -1 (-2325 2100)(-2325 2050);
WIRE 16 -1 (-2325 2050)(-2075 2050);
WIRE 16 -1 (-2325 2000)(-2075 2000);
WIRE 16 -1 (-2325 2050)(-2325 2000);
WIRE 16 -1 (-2325 2000)(-2325 1950);
WIRE 16 -1 (-2325 1950)(-2075 1950);
WIRE 16 -1 (-2325 1950)(-2325 1900);
WIRE 16 -1 (-2325 1900)(-2075 1900);
WIRE 16 -1 (-2325 1900)(-2325 1850);
WIRE 16 -1 (-2325 1850)(-2075 1850);
WIRE 16 -1 (-2325 1850)(-2325 1800);
WIRE 16 -1 (-2325 1800)(-2075 1800);
WIRE 16 -1 (-2325 1800)(-2325 1750);
WIRE 16 -1 (-2325 1750)(-2075 1750);
WIRE 16 -1 (-2325 1750)(-2325 1700);
WIRE 16 -1 (-2325 1700)(-2075 1700);
WIRE 16 -1 (-2325 1700)(-2325 1650);
WIRE 16 -1 (-2325 1650)(-2075 1650);
WIRE 16 -1 (-2325 1650)(-2325 1600);
WIRE 16 -1 (-2075 1600)(-2325 1600);
WIRE 16 -1 (-2325 1600)(-2325 1550);
WIRE 16 -1 (-2325 1550)(-2075 1550);
WIRE 16 -1 (-2325 1500)(-2075 1500);
WIRE 16 -1 (-2325 1550)(-2325 1500);
WIRE 16 -1 (-2325 1500)(-2325 1450);
WIRE 16 -1 (-2325 1450)(-2075 1450);
WIRE 16 -1 (-2325 1450)(-2325 1400);
WIRE 16 -1 (-2325 1400)(-2075 1400);
WIRE 16 -1 (-2325 1400)(-2325 1350);
WIRE 16 -1 (-2325 1350)(-2075 1350);
WIRE 16 -1 (2050 1250)(2300 1250);
WIRE 16 -1 (2050 1300)(2050 1250);
WIRE 16 -1 (2050 1300)(2300 1300);
WIRE 16 -1 (1350 1175)(1350 1300);
WIRE 16 -1 (1350 1300)(2050 1300);
WIRE 16 -1 (2300 3300)(2050 3300);
WIRE 16 -1 (2050 3300)(2050 3250);
WIRE 16 -1 (2300 3250)(2050 3250);
WIRE 16 -1 (2050 3250)(2050 3200);
WIRE 16 -1 (2300 3200)(2050 3200);
WIRE 16 -1 (2050 3200)(2050 3150);
WIRE 16 -1 (2300 3150)(2050 3150);
WIRE 16 -1 (2050 3150)(2050 3100);
WIRE 16 -1 (2300 3100)(2050 3100);
WIRE 16 -1 (2300 3050)(2050 3050);
WIRE 16 -1 (2050 3100)(2050 3050);
WIRE 16 -1 (2050 3050)(2050 3000);
WIRE 16 -1 (2300 3000)(2050 3000);
WIRE 16 -1 (2050 3000)(2050 2950);
WIRE 16 -1 (2300 2950)(2050 2950);
WIRE 16 -1 (2050 2950)(2050 2900);
WIRE 16 -1 (2300 2900)(2050 2900);
WIRE 16 -1 (2050 2900)(2050 2850);
WIRE 16 -1 (2050 2850)(2300 2850);
WIRE 16 -1 (2050 2800)(2300 2800);
WIRE 16 -1 (2050 2850)(2050 2800);
WIRE 16 -1 (2050 2800)(2050 2750);
WIRE 16 -1 (2300 2750)(2050 2750);
WIRE 16 -1 (2050 2750)(2050 2700);
WIRE 16 -1 (2050 2700)(2300 2700);
WIRE 16 -1 (2050 2700)(2050 2650);
WIRE 16 -1 (2050 2650)(2300 2650);
WIRE 16 -1 (2050 2650)(2050 2600);
WIRE 16 -1 (2050 2600)(2300 2600);
WIRE 16 -1 (2050 2550)(2300 2550);
WIRE 16 -1 (2050 2600)(2050 2550);
WIRE 16 -1 (2050 2550)(2050 2500);
WIRE 16 -1 (2050 2500)(2300 2500);
WIRE 16 -1 (2050 2500)(2050 2450);
WIRE 16 -1 (2050 2450)(2300 2450);
WIRE 16 -1 (2050 2450)(2050 2400);
WIRE 16 -1 (2050 2400)(2300 2400);
WIRE 16 -1 (2050 2400)(2050 2350);
WIRE 16 -1 (2050 2350)(2300 2350);
WIRE 16 -1 (2050 2300)(2300 2300);
WIRE 16 -1 (2050 2350)(2050 2300);
WIRE 16 -1 (2050 2300)(2050 2250);
WIRE 16 -1 (2050 2250)(2300 2250);
WIRE 16 -1 (2050 2250)(2050 2200);
WIRE 16 -1 (2050 2200)(2300 2200);
WIRE 16 -1 (2050 2200)(2050 2150);
WIRE 16 -1 (2050 2150)(2300 2150);
WIRE 16 -1 (2050 2150)(2050 2100);
WIRE 16 -1 (2050 2100)(2300 2100);
WIRE 16 -1 (2050 2100)(2050 2050);
WIRE 16 -1 (2050 2050)(2300 2050);
WIRE 16 -1 (2050 2000)(2300 2000);
WIRE 16 -1 (2050 2050)(2050 2000);
WIRE 16 -1 (2050 2000)(2050 1950);
WIRE 16 -1 (2050 1950)(2300 1950);
WIRE 16 -1 (2050 1950)(2050 1900);
WIRE 16 -1 (2050 1900)(2300 1900);
WIRE 16 -1 (4950 300)(4700 300);
WIRE 16 -1 (4950 350)(4700 350);
WIRE 16 -1 (4950 350)(4950 300);
WIRE 16 -1 (4950 400)(4700 400);
WIRE 16 -1 (4950 400)(4950 350);
WIRE 16 -1 (4950 450)(4700 450);
WIRE 16 -1 (4950 450)(4950 400);
WIRE 16 -1 (4950 500)(4700 500);
WIRE 16 -1 (4950 500)(4950 450);
WIRE 16 -1 (4950 550)(4950 500);
WIRE 16 -1 (4950 550)(4700 550);
WIRE 16 -1 (4700 600)(4950 600);
WIRE 16 -1 (4950 600)(4950 550);
WIRE 16 -1 (4700 650)(4950 650);
WIRE 16 -1 (4950 650)(4950 600);
WIRE 16 -1 (4700 700)(4950 700);
WIRE 16 -1 (4950 700)(4950 650);
WIRE 16 -1 (4700 750)(4950 750);
WIRE 16 -1 (4950 750)(4950 700);
WIRE 16 -1 (4950 750)(5300 750);
WIRE 16 -1 (4950 3550)(4700 3550);
WIRE 16 -1 (4950 3500)(4700 3500);
WIRE 16 -1 (4950 3550)(4950 3500);
WIRE 16 -1 (4950 3450)(4700 3450);
WIRE 16 -1 (4950 3500)(4950 3450);
WIRE 16 -1 (4950 3400)(4700 3400);
WIRE 16 -1 (4950 3450)(4950 3400);
WIRE 16 -1 (4950 3350)(4700 3350);
WIRE 16 -1 (4950 3400)(4950 3350);
WIRE 16 -1 (4950 3300)(4700 3300);
WIRE 16 -1 (4950 3350)(4950 3300);
WIRE 16 -1 (4950 3250)(4700 3250);
WIRE 16 -1 (4950 3300)(4950 3250);
WIRE 16 -1 (4950 3200)(4700 3200);
WIRE 16 -1 (4950 3250)(4950 3200);
WIRE 16 -1 (4950 3150)(4700 3150);
WIRE 16 -1 (4950 3200)(4950 3150);
WIRE 16 -1 (4950 3100)(4700 3100);
WIRE 16 -1 (4950 3150)(4950 3100);
WIRE 16 -1 (4950 3050)(4700 3050);
WIRE 16 -1 (4950 3100)(4950 3050);
WIRE 16 -1 (4950 3000)(4700 3000);
WIRE 16 -1 (4950 3050)(4950 3000);
WIRE 16 -1 (4950 2950)(4700 2950);
WIRE 16 -1 (4950 3000)(4950 2950);
WIRE 16 -1 (4950 2900)(4700 2900);
WIRE 16 -1 (4950 2950)(4950 2900);
WIRE 16 -1 (4950 2850)(4700 2850);
WIRE 16 -1 (4950 2900)(4950 2850);
WIRE 16 -1 (4950 2800)(4700 2800);
WIRE 16 -1 (4950 2850)(4950 2800);
WIRE 16 -1 (4950 2750)(4700 2750);
WIRE 16 -1 (4950 2800)(4950 2750);
WIRE 16 -1 (4950 2700)(4700 2700);
WIRE 16 -1 (4950 2750)(4950 2700);
WIRE 16 -1 (4950 2650)(4700 2650);
WIRE 16 -1 (4950 2700)(4950 2650);
WIRE 16 -1 (4700 2600)(4950 2600);
WIRE 16 -1 (4950 2650)(4950 2600);
WIRE 16 -1 (4700 2550)(4950 2550);
WIRE 16 -1 (4950 2600)(4950 2550);
WIRE 16 -1 (4700 2500)(4950 2500);
WIRE 16 -1 (4950 2550)(4950 2500);
WIRE 16 -1 (4700 2450)(4950 2450);
WIRE 16 -1 (4950 2500)(4950 2450);
WIRE 16 -1 (4700 2400)(4950 2400);
WIRE 16 -1 (4950 2450)(4950 2400);
WIRE 16 -1 (4700 2350)(4950 2350);
WIRE 16 -1 (4950 2400)(4950 2350);
WIRE 16 -1 (4700 2300)(4950 2300);
WIRE 16 -1 (4950 2350)(4950 2300);
WIRE 16 -1 (4700 2250)(4950 2250);
WIRE 16 -1 (4950 2300)(4950 2250);
WIRE 16 -1 (4700 2200)(4950 2200);
WIRE 16 -1 (4950 2250)(4950 2200);
WIRE 16 -1 (4700 2150)(4950 2150);
WIRE 16 -1 (4950 2200)(4950 2150);
WIRE 16 -1 (4700 2100)(4950 2100);
WIRE 16 -1 (4950 2150)(4950 2100);
WIRE 16 -1 (4700 2050)(4950 2050);
WIRE 16 -1 (4950 2100)(4950 2050);
WIRE 16 -1 (4700 2000)(4950 2000);
WIRE 16 -1 (4950 2050)(4950 2000);
WIRE 16 -1 (4700 1950)(4950 1950);
WIRE 16 -1 (4950 2000)(4950 1950);
WIRE 16 -1 (4700 1900)(4950 1900);
WIRE 16 -1 (4950 1950)(4950 1900);
WIRE 16 -1 (4700 1850)(4950 1850);
WIRE 16 -1 (4950 1900)(4950 1850);
WIRE 16 -1 (4700 1800)(4950 1800);
WIRE 16 -1 (4950 1850)(4950 1800);
WIRE 16 -1 (4700 1750)(4950 1750);
WIRE 16 -1 (4950 1800)(4950 1750);
WIRE 16 -1 (4700 1700)(4950 1700);
WIRE 16 -1 (4950 1750)(4950 1700);
WIRE 16 -1 (4950 1700)(4950 1650);
WIRE 16 -1 (4700 1650)(4950 1650);
WIRE 16 -1 (4700 1450)(4950 1450);
WIRE 16 -1 (4950 1450)(4950 1400);
WIRE 16 -1 (4700 1400)(4950 1400);
WIRE 16 -1 (4950 1400)(5300 1400);
WIRE 16 -1 (2050 1500)(2300 1500);
WIRE 16 -1 (2050 1550)(2050 1500);
WIRE 16 -1 (2050 1550)(2300 1550);
WIRE 16 -1 (2050 1000)(2300 1000);
WIRE 16 -1 (2050 950)(2050 1000);
WIRE 16 -1 (2050 950)(2300 950);
WIRE 16 -1 (2050 950)(2050 900);
WIRE 16 -1 (2050 900)(2300 900);
WIRE 16 -1 (2050 900)(2050 850);
WIRE 16 -1 (2050 850)(2300 850);
WIRE 16 -1 (2050 850)(2050 800);
WIRE 16 -1 (2050 800)(2300 800);
DOT 1 (575 3300);
DOT 1 (2050 2900);
DOT 1 (2050 2700);
DOT 1 (4950 3500);
DOT 1 (4950 3550);
DOT 1 (4950 3450);
DOT 1 (4950 3400);
DOT 1 (4950 3350);
DOT 1 (4950 3250);
DOT 1 (4950 3300);
DOT 1 (4950 3200);
DOT 1 (4950 3150);
DOT 1 (4950 3100);
DOT 1 (4950 3050);
DOT 1 (4950 3000);
DOT 1 (4950 2950);
DOT 1 (4950 2900);
DOT 1 (4950 2850);
DOT 1 (4950 2800);
DOT 1 (4950 2750);
DOT 1 (4950 2700);
DOT 1 (4950 2650);
DOT 1 (4950 2600);
DOT 1 (4950 2550);
DOT 1 (4950 2500);
DOT 1 (4950 2450);
DOT 1 (4950 2400);
DOT 1 (4950 2350);
DOT 1 (4950 2300);
DOT 1 (4950 2250);
DOT 1 (4950 2200);
DOT 1 (4950 2150);
DOT 1 (4950 2100);
DOT 1 (4950 2050);
DOT 1 (4950 2000);
DOT 1 (4950 1950);
DOT 1 (4950 1900);
DOT 1 (4950 1850);
DOT 1 (4950 1800);
DOT 1 (4950 1700);
DOT 1 (4950 1750);
DOT 1 (4950 1400);
DOT 1 (4950 750);
DOT 1 (4950 700);
DOT 1 (4950 650);
DOT 1 (4950 550);
DOT 1 (4950 600);
DOT 1 (4950 500);
DOT 1 (4950 450);
DOT 1 (4950 400);
DOT 1 (4950 350);
DOT 1 (2050 850);
DOT 1 (2050 900);
DOT 1 (2050 950);
DOT 1 (2050 1000);
DOT 1 (2050 1300);
DOT 1 (2050 1550);
DOT 1 (2050 1950);
DOT 1 (2050 2000);
DOT 1 (2050 2050);
DOT 1 (2050 2100);
DOT 1 (2050 2150);
DOT 1 (2050 2200);
DOT 1 (2050 2250);
DOT 1 (2050 2300);
DOT 1 (2050 2350);
DOT 1 (2050 2400);
DOT 1 (2050 2450);
DOT 1 (2050 2500);
DOT 1 (2050 2550);
DOT 1 (2050 2600);
DOT 1 (2050 2650);
DOT 1 (2050 2750);
DOT 1 (2050 2800);
DOT 1 (2050 2850);
DOT 1 (2050 2950);
DOT 1 (2050 3000);
DOT 1 (2050 3050);
DOT 1 (2050 3150);
DOT 1 (2050 3100);
DOT 1 (2050 3200);
DOT 1 (2050 3250);
DOT 1 (2050 3300);
DOT 1 (575 3250);
DOT 1 (575 3150);
DOT 1 (575 3200);
DOT 1 (575 3000);
DOT 1 (575 3050);
DOT 1 (575 2950);
DOT 1 (575 2750);
DOT 1 (575 2800);
DOT 1 (575 2700);
DOT 1 (575 2600);
DOT 1 (575 2650);
DOT 1 (575 2450);
DOT 1 (575 2500);
DOT 1 (575 2550);
DOT 1 (575 2350);
DOT 1 (575 2400);
DOT 1 (575 2300);
DOT 1 (1350 1300);
DOT 1 (-2325 3250);
DOT 1 (-2325 3300);
DOT 1 (-2325 3100);
DOT 1 (-2325 3150);
DOT 1 (-2325 3200);
DOT 1 (-2325 3050);
DOT 1 (-2325 3000);
DOT 1 (-2325 2950);
DOT 1 (-2325 2850);
DOT 1 (-2325 2900);
DOT 1 (-2325 2800);
DOT 1 (-2325 2750);
DOT 1 (-2325 2700);
DOT 1 (-2325 2600);
DOT 1 (-2325 2650);
DOT 1 (-2325 2550);
DOT 1 (-2325 2500);
DOT 1 (-2325 2450);
DOT 1 (-2325 2350);
DOT 1 (-2325 2400);
DOT 1 (-2325 2300);
DOT 1 (-2325 2250);
DOT 1 (-2325 2200);
DOT 1 (-2325 2150);
DOT 1 (-2325 2100);
DOT 1 (-2325 2050);
DOT 1 (-2325 2000);
DOT 1 (-2325 1950);
DOT 1 (-2325 1900);
DOT 1 (-2325 1850);
DOT 1 (-2325 1800);
DOT 1 (-2325 1700);
DOT 1 (-2325 1750);
DOT 1 (-2325 1650);
DOT 1 (-2325 1550);
DOT 1 (-2325 1600);
DOT 1 (-2325 1500);
DOT 1 (-2325 1450);
DOT 1 (-2325 1400);
DOT 1 (575 2850);
DOT 1 (575 2900);
QUIT
